# SCM (Grand Teton) — schematic netlist excerpt (pin names and nets, part order shuffled) for the footprints in the layout excerpt that follows; sources: Cadence DE-HDL packaged netlist, KiCad conversion of 12092022_DA0F0TMDCD0_F0T_Management_Board_D_brd_V3_OCP.brd

R848  Q_RES  4.7K 1% CHIP  pkg 0402LF  page 27 : A = P3V3_AUX ; B = SMB_BMC_ALERT16_N
R785  Q_RES  15.8K 1% CHIP  pkg 0402LF  page 15 : A = P12V_AUX ; B = P12V_SENSOR

(kicad_pcb
	(version 20260206)
	(generator "pcbnew")
	(generator_version "10.0")
	(general
		(thickness 1.6)
		(legacy_teardrops no)
	)
	(paper "A4")
	(title_block
		(title "12092022_DA0F0TMDCD0_F0T_Management_Board_D_brd_V3_OCP.brd")
		(comment 1 "Grand Teton / footprints 791-792 of 1440")
	)
	(layers
		(0 "F.Cu" signal "TOP")
		(4 "In1.Cu" signal "GND")
		(6 "In2.Cu" signal "IN1")
		(8 "In3.Cu" signal "GND1")
		(10 "In4.Cu" signal "IN2")
		(12 "In5.Cu" signal "VCC")
		(14 "In6.Cu" signal "VCC1")
		(16 "In7.Cu" signal "IN3")
		(18 "In8.Cu" signal "GND2")
		(20 "In9.Cu" signal "IN4")
		(22 "In10.Cu" signal "GND3")
		(2 "B.Cu" signal "BOTTOM")
		(9 "F.Adhes" user "F.Adhesive")
		(11 "B.Adhes" user "B.Adhesive")
		(13 "F.Paste" user "Package Geometry/Pastemask Top")
		(15 "B.Paste" user "Package Geometry/Pastemask Bottom")
		(5 "F.SilkS" user "Ref Des/Silkscreen Top")
		(7 "B.SilkS" user "Ref Des/Silkscreen Bottom")
		(1 "F.Mask" user "Board Geometry/Soldermask Top")
		(3 "B.Mask" user "Board Geometry/Soldermask Bottom")
		(17 "Dwgs.User" user "User.Drawings")
		(19 "Cmts.User" user "User.Comments")
		(21 "Eco1.User" user "User.Eco1")
		(23 "Eco2.User" user "User.Eco2")
		(25 "Edge.Cuts" user "Board Geometry/Outline")
		(27 "Margin" user)
		(31 "F.CrtYd" user "Package Geometry/Place Bound Top")
		(29 "B.CrtYd" user "Package Geometry/Place Bound Bottom")
		(35 "F.Fab" user "Ref Des/Assembly Top")
		(33 "B.Fab" user "Ref Des/Assembly Bottom")
	)
	(footprint ""
		(layer "B.Cu")
		(at 32.396684 -58.349388 -90)
		(property "Reference" "R785"
			(at 0 0 90)
			(layer "B.SilkS")
			(hide yes)
			(effects
				(font
					(size 1.27 1.27)
				)
				(justify mirror)
			)
		)
		(property "Value" ""
			(at 0 0 90)
			(layer "B.Fab")
			(effects
				(font
					(size 1.27 1.27)
				)
				(justify mirror)
			)
		)
		(duplicate_pad_numbers_are_jumpers no)
		(fp_line
			(start -0.7874 0.4064)
			(end 0.7874 0.4064)
			(stroke
				(width 0.1524)
				(type default)
			)
			(layer "B.SilkS")
		)
		(fp_line
			(start 0.7874 0.4064)
			(end 0.7874 -0.4064)
			(stroke
				(width 0.1524)
				(type default)
			)
			(layer "B.SilkS")
		)
		(fp_line
			(start -0.7874 -0.4064)
			(end -0.7874 0.4064)
			(stroke
				(width 0.1524)
				(type default)
			)
			(layer "B.SilkS")
		)
		(fp_line
			(start 0.7874 -0.4064)
			(end -0.7874 -0.4064)
			(stroke
				(width 0.1524)
				(type default)
			)
			(layer "B.SilkS")
		)
		(fp_line
			(start -0.67945 0.3048)
			(end -0.120396 0.3048)
			(stroke
				(width 0.1)
				(type default)
			)
			(layer "B.Fab")
		)
		(fp_line
			(start -0.120396 0.3048)
			(end -0.120396 0.2794)
			(stroke
				(width 0.1)
				(type default)
			)
			(layer "B.Fab")
		)
		(fp_line
			(start 0.12065 0.3048)
			(end 0.67945 0.3048)
			(stroke
				(width 0.1)
				(type default)
			)
			(layer "B.Fab")
		)
		(fp_line
			(start 0.67945 0.3048)
			(end 0.67945 -0.305054)
			(stroke
				(width 0.1)
				(type default)
			)
			(layer "B.Fab")
		)
		(fp_line
			(start -0.120396 0.2794)
			(end 0.12065 0.2794)
			(stroke
				(width 0.1)
				(type default)
			)
			(layer "B.Fab")
		)
		(fp_line
			(start 0.12065 0.2794)
			(end 0.12065 0.3048)
			(stroke
				(width 0.1)
				(type default)
			)
			(layer "B.Fab")
		)
		(fp_line
			(start -0.12065 -0.2794)
			(end -0.12065 -0.3048)
			(stroke
				(width 0.1)
				(type default)
			)
			(layer "B.Fab")
		)
		(fp_line
			(start 0.12065 -0.2794)
			(end -0.12065 -0.2794)
			(stroke
				(width 0.1)
				(type default)
			)
			(layer "B.Fab")
		)
		(fp_line
			(start -0.67945 -0.3048)
			(end -0.67945 0.3048)
			(stroke
				(width 0.1)
				(type default)
			)
			(layer "B.Fab")
		)
		(fp_line
			(start -0.12065 -0.3048)
			(end -0.67945 -0.3048)
			(stroke
				(width 0.1)
				(type default)
			)
			(layer "B.Fab")
		)
		(fp_line
			(start 0.12065 -0.305054)
			(end 0.12065 -0.2794)
			(stroke
				(width 0.1)
				(type default)
			)
			(layer "B.Fab")
		)
		(fp_line
			(start 0.67945 -0.305054)
			(end 0.12065 -0.305054)
			(stroke
				(width 0.1)
				(type default)
			)
			(layer "B.Fab")
		)
		(pad "1" smd circle
			(at 0.40005 0 90)
			(size 0 0)
			(layers "B.Cu" "B.Mask" "B.Paste")
			(net "P12V_AUX")
		)
		(pad "2" smd circle
			(at -0.40005 0 90)
			(size 0 0)
			(layers "B.Cu" "B.Mask" "B.Paste")
			(net "P12V_SENSOR")
		)
	)
	(footprint ""
		(layer "B.Cu")
		(at 48.436022 -62.116462 90)
		(property "Reference" "R848"
			(at 0 0 90)
			(layer "B.SilkS")
			(hide yes)
			(effects
				(font
					(size 1.27 1.27)
				)
				(justify mirror)
			)
		)
		(property "Value" ""
			(at 0 0 90)
			(layer "B.Fab")
			(effects
				(font
					(size 1.27 1.27)
				)
				(justify mirror)
			)
		)
		(duplicate_pad_numbers_are_jumpers no)
		(fp_line
			(start 0.7874 -0.4064)
			(end -0.7874 -0.4064)
			(stroke
				(width 0.1524)
				(type default)
			)
			(layer "B.SilkS")
		)
		(fp_line
			(start -0.7874 -0.4064)
			(end -0.7874 0.4064)
			(stroke
				(width 0.1524)
				(type default)
			)
			(layer "B.SilkS")
		)
		(fp_line
			(start 0.7874 0.4064)
			(end 0.7874 -0.4064)
			(stroke
				(width 0.1524)
				(type default)
			)
			(layer "B.SilkS")
		)
		(fp_line
			(start -0.7874 0.4064)
			(end 0.7874 0.4064)
			(stroke
				(width 0.1524)
				(type default)
			)
			(layer "B.SilkS")
		)
		(fp_line
			(start 0.67945 -0.305054)
			(end 0.12065 -0.305054)
			(stroke
				(width 0.1)
				(type default)
			)
			(layer "B.Fab")
		)
		(fp_line
			(start 0.12065 -0.305054)
			(end 0.12065 -0.2794)
			(stroke
				(width 0.1)
				(type default)
			)
			(layer "B.Fab")
		)
		(fp_line
			(start -0.12065 -0.3048)
			(end -0.67945 -0.3048)
			(stroke
				(width 0.1)
				(type default)
			)
			(layer "B.Fab")
		)
		(fp_line
			(start -0.67945 -0.3048)
			(end -0.67945 0.3048)
			(stroke
				(width 0.1)
				(type default)
			)
			(layer "B.Fab")
		)
		(fp_line
			(start 0.12065 -0.2794)
			(end -0.12065 -0.2794)
			(stroke
				(width 0.1)
				(type default)
			)
			(layer "B.Fab")
		)
		(fp_line
			(start -0.12065 -0.2794)
			(end -0.12065 -0.3048)
			(stroke
				(width 0.1)
				(type default)
			)
			(layer "B.Fab")
		)
		(fp_line
			(start 0.12065 0.2794)
			(end 0.12065 0.3048)
			(stroke
				(width 0.1)
				(type default)
			)
			(layer "B.Fab")
		)
		(fp_line
			(start -0.120396 0.2794)
			(end 0.12065 0.2794)
			(stroke
				(width 0.1)
				(type default)
			)
			(layer "B.Fab")
		)
		(fp_line
			(start 0.67945 0.3048)
			(end 0.67945 -0.305054)
			(stroke
				(width 0.1)
				(type default)
			)
			(layer "B.Fab")
		)
		(fp_line
			(start 0.12065 0.3048)
			(end 0.67945 0.3048)
			(stroke
				(width 0.1)
				(type default)
			)
			(layer "B.Fab")
		)
		(fp_line
			(start -0.120396 0.3048)
			(end -0.120396 0.2794)
			(stroke
				(width 0.1)
				(type default)
			)
			(layer "B.Fab")
		)
		(fp_line
			(start -0.67945 0.3048)
			(end -0.120396 0.3048)
			(stroke
				(width 0.1)
				(type default)
			)
			(layer "B.Fab")
		)
		(pad "1" smd circle
			(at 0.40005 0 270)
			(size 0 0)
			(layers "B.Cu" "B.Mask" "B.Paste")
			(net "P3V3_AUX")
		)
		(pad "2" smd circle
			(at -0.40005 0 270)
			(size 0 0)
			(layers "B.Cu" "B.Mask" "B.Paste")
			(net "SMB_BMC_ALERT16_N")
		)
	)
)
